(kicad_pcb
	(version 20260206)
	(generator "pcbnew")
	(generator_version "10.0")
	(general
		(thickness 1.6)
		(legacy_teardrops no)
	)
	(paper "A4")
	(title_block
		(title "04192023_DAF0TMB3IC0_F0TG_MB_C_brd_V02_OCP.brd")
		(comment 1 "Grand Teton / footprints 4957-4965 of 8354")
	)
	(layers
		(0 "F.Cu" signal "TOP")
		(4 "In1.Cu" signal "GND")
		(6 "In2.Cu" signal "IN1")
		(8 "In3.Cu" signal "GND1")
		(10 "In4.Cu" signal "IN2")
		(12 "In5.Cu" signal "GND2")
		(14 "In6.Cu" signal "IN3")
		(16 "In7.Cu" signal "GND3")
		(18 "In8.Cu" signal "VCC")
		(20 "In9.Cu" signal "VCC1")
		(22 "In10.Cu" signal "GND4")
		(24 "In11.Cu" signal "IN4")
		(26 "In12.Cu" signal "GND5")
		(28 "In13.Cu" signal "IN5")
		(30 "In14.Cu" signal "GND6")
		(32 "In15.Cu" signal "IN6")
		(34 "In16.Cu" signal "GND7")
		(2 "B.Cu" signal "BOTTOM")
		(9 "F.Adhes" user "F.Adhesive")
		(11 "B.Adhes" user "B.Adhesive")
		(13 "F.Paste" user "Package Geometry/Pastemask Top")
		(15 "B.Paste" user "Package Geometry/Pastemask Bottom")
		(5 "F.SilkS" user "Ref Des/Silkscreen Top")
		(7 "B.SilkS" user "Ref Des/Silkscreen Bottom")
		(1 "F.Mask" user "Board Geometry/Soldermask Top")
		(3 "B.Mask" user "Board Geometry/Soldermask Bottom")
		(17 "Dwgs.User" user "User.Drawings")
		(19 "Cmts.User" user "User.Comments")
		(21 "Eco1.User" user "User.Eco1")
		(23 "Eco2.User" user "User.Eco2")
		(25 "Edge.Cuts" user "Board Geometry/Outline")
		(27 "Margin" user)
		(31 "F.CrtYd" user "Package Geometry/Place Bound Top")
		(29 "B.CrtYd" user "Package Geometry/Place Bound Bottom")
		(35 "F.Fab" user "Ref Des/Assembly Top")
		(33 "B.Fab" user "Ref Des/Assembly Bottom")
	)
	(footprint ""
		(layer "B.Cu")
		(at 359.539794 -419.027864 180)
		(property "Reference" "R2838"
			(at 0 0 0)
			(layer "B.SilkS")
			(hide yes)
			(effects
				(font
					(size 1.27 1.27)
				)
				(justify mirror)
			)
		)
		(property "Value" ""
			(at 0 0 0)
			(layer "B.Fab")
			(effects
				(font
					(size 1.27 1.27)
				)
				(justify mirror)
			)
		)
		(duplicate_pad_numbers_are_jumpers no)
		(fp_line
			(start 0.7874 0.4064)
			(end 0.7874 -0.4064)
			(stroke
				(width 0.1524)
				(type default)
			)
			(layer "B.SilkS")
		)
		(fp_line
			(start 0.7874 -0.4064)
			(end -0.7874 -0.4064)
			(stroke
				(width 0.1524)
				(type default)
			)
			(layer "B.SilkS")
		)
		(fp_line
			(start -0.7874 0.4064)
			(end 0.7874 0.4064)
			(stroke
				(width 0.1524)
				(type default)
			)
			(layer "B.SilkS")
		)
		(fp_line
			(start -0.7874 -0.4064)
			(end -0.7874 0.4064)
			(stroke
				(width 0.1524)
				(type default)
			)
			(layer "B.SilkS")
		)
		(fp_line
			(start 0.67945 0.3048)
			(end 0.67945 -0.305054)
			(stroke
				(width 0.1)
				(type default)
			)
			(layer "B.Fab")
		)
		(fp_line
			(start 0.67945 -0.305054)
			(end 0.12065 -0.305054)
			(stroke
				(width 0.1)
				(type default)
			)
			(layer "B.Fab")
		)
		(fp_line
			(start 0.12065 0.3048)
			(end 0.67945 0.3048)
			(stroke
				(width 0.1)
				(type default)
			)
			(layer "B.Fab")
		)
		(fp_line
			(start 0.12065 0.2794)
			(end 0.12065 0.3048)
			(stroke
				(width 0.1)
				(type default)
			)
			(layer "B.Fab")
		)
		(fp_line
			(start 0.12065 -0.2794)
			(end -0.12065 -0.2794)
			(stroke
				(width 0.1)
				(type default)
			)
			(layer "B.Fab")
		)
		(fp_line
			(start 0.12065 -0.305054)
			(end 0.12065 -0.2794)
			(stroke
				(width 0.1)
				(type default)
			)
			(layer "B.Fab")
		)
		(fp_line
			(start -0.120396 0.3048)
			(end -0.120396 0.2794)
			(stroke
				(width 0.1)
				(type default)
			)
			(layer "B.Fab")
		)
		(fp_line
			(start -0.120396 0.2794)
			(end 0.12065 0.2794)
			(stroke
				(width 0.1)
				(type default)
			)
			(layer "B.Fab")
		)
		(fp_line
			(start -0.12065 -0.2794)
			(end -0.12065 -0.3048)
			(stroke
				(width 0.1)
				(type default)
			)
			(layer "B.Fab")
		)
		(fp_line
			(start -0.12065 -0.3048)
			(end -0.67945 -0.3048)
			(stroke
				(width 0.1)
				(type default)
			)
			(layer "B.Fab")
		)
		(fp_line
			(start -0.67945 0.3048)
			(end -0.120396 0.3048)
			(stroke
				(width 0.1)
				(type default)
			)
			(layer "B.Fab")
		)
		(fp_line
			(start -0.67945 -0.3048)
			(end -0.67945 0.3048)
			(stroke
				(width 0.1)
				(type default)
			)
			(layer "B.Fab")
		)
		(pad "1" smd circle
			(at 0.40005 0)
			(size 0 0)
			(layers "B.Cu" "B.Mask" "B.Paste")
			(net "FM_SWB_PWRGD")
		)
		(pad "2" smd circle
			(at -0.40005 0)
			(size 0 0)
			(layers "B.Cu" "B.Mask" "B.Paste")
			(net "GND")
		)
	)
	(footprint ""
		(layer "B.Cu")
		(at 58.418476 -338.086954 -90)
		(property "Reference" "PC419_3"
			(at 0 0 90)
			(layer "B.SilkS")
			(hide yes)
			(effects
				(font
					(size 1.27 1.27)
				)
				(justify mirror)
			)
		)
		(property "Value" ""
			(at 0 0 90)
			(layer "B.Fab")
			(effects
				(font
					(size 1.27 1.27)
				)
				(justify mirror)
			)
		)
		(duplicate_pad_numbers_are_jumpers no)
		(fp_line
			(start -1.524 0.762)
			(end 1.524 0.762)
			(stroke
				(width 0.1524)
				(type default)
			)
			(layer "B.SilkS")
		)
		(fp_line
			(start 1.524 0.762)
			(end 1.524 -0.762)
			(stroke
				(width 0.1524)
				(type default)
			)
			(layer "B.SilkS")
		)
		(fp_line
			(start -1.524 -0.762)
			(end -1.524 0.762)
			(stroke
				(width 0.1524)
				(type default)
			)
			(layer "B.SilkS")
		)
		(fp_line
			(start 1.524 -0.762)
			(end -1.524 -0.762)
			(stroke
				(width 0.1524)
				(type default)
			)
			(layer "B.SilkS")
		)
		(fp_line
			(start -1.1049 0.724916)
			(end -1.1049 -0.724916)
			(stroke
				(width 0.1)
				(type default)
			)
			(layer "B.Fab")
		)
		(fp_line
			(start 1.1049 0.724916)
			(end -1.1049 0.724916)
			(stroke
				(width 0.1)
				(type default)
			)
			(layer "B.Fab")
		)
		(fp_line
			(start -1.1049 -0.724916)
			(end 1.1049 -0.724916)
			(stroke
				(width 0.1)
				(type default)
			)
			(layer "B.Fab")
		)
		(fp_line
			(start 1.1049 -0.724916)
			(end 1.1049 0.724916)
			(stroke
				(width 0.1)
				(type default)
			)
			(layer "B.Fab")
		)
		(pad "1" smd rect
			(at 0.889 0 270)
			(size 1.016 1.27)
			(layers "B.Cu" "B.Mask" "B.Paste")
			(net "PVDDCR_CPU1_P1")
		)
		(pad "2" smd rect
			(at -0.889 0 270)
			(size 1.016 1.27)
			(layers "B.Cu" "B.Mask" "B.Paste")
			(net "GND")
		)
	)
	(footprint ""
		(layer "B.Cu")
		(at 386.350256 -182.867554 -90)
		(property "Reference" "PC559_4"
			(at 0 0 90)
			(layer "B.SilkS")
			(hide yes)
			(effects
				(font
					(size 1.27 1.27)
				)
				(justify mirror)
			)
		)
		(property "Value" ""
			(at 0 0 90)
			(layer "B.Fab")
			(effects
				(font
					(size 1.27 1.27)
				)
				(justify mirror)
			)
		)
		(duplicate_pad_numbers_are_jumpers no)
		(fp_line
			(start -1.524 0.762)
			(end 1.524 0.762)
			(stroke
				(width 0.1524)
				(type default)
			)
			(layer "B.SilkS")
		)
		(fp_line
			(start 1.524 0.762)
			(end 1.524 -0.762)
			(stroke
				(width 0.1524)
				(type default)
			)
			(layer "B.SilkS")
		)
		(fp_line
			(start -1.524 -0.762)
			(end -1.524 0.762)
			(stroke
				(width 0.1524)
				(type default)
			)
			(layer "B.SilkS")
		)
		(fp_line
			(start 1.524 -0.762)
			(end -1.524 -0.762)
			(stroke
				(width 0.1524)
				(type default)
			)
			(layer "B.SilkS")
		)
		(fp_line
			(start -1.1049 0.724916)
			(end -1.1049 -0.724916)
			(stroke
				(width 0.1)
				(type default)
			)
			(layer "B.Fab")
		)
		(fp_line
			(start 1.1049 0.724916)
			(end -1.1049 0.724916)
			(stroke
				(width 0.1)
				(type default)
			)
			(layer "B.Fab")
		)
		(fp_line
			(start -1.1049 -0.724916)
			(end 1.1049 -0.724916)
			(stroke
				(width 0.1)
				(type default)
			)
			(layer "B.Fab")
		)
		(fp_line
			(start 1.1049 -0.724916)
			(end 1.1049 0.724916)
			(stroke
				(width 0.1)
				(type default)
			)
			(layer "B.Fab")
		)
		(pad "1" smd rect
			(at 0.889 0 270)
			(size 1.016 1.27)
			(layers "B.Cu" "B.Mask" "B.Paste")
			(net "SW_P12V_AUX_PVDDCR_CPU0_P0_FLT")
		)
		(pad "2" smd rect
			(at -0.889 0 270)
			(size 1.016 1.27)
			(layers "B.Cu" "B.Mask" "B.Paste")
			(net "GND")
		)
	)
	(footprint ""
		(layer "B.Cu")
		(at 99.128834 -250.892564 180)
		(property "Reference" "C2669"
			(at 0 0 0)
			(layer "B.SilkS")
			(hide yes)
			(effects
				(font
					(size 1.27 1.27)
				)
				(justify mirror)
			)
		)
		(property "Value" ""
			(at 0 0 0)
			(layer "B.Fab")
			(effects
				(font
					(size 1.27 1.27)
				)
				(justify mirror)
			)
		)
		(duplicate_pad_numbers_are_jumpers no)
		(fp_line
			(start 0.7874 0.4064)
			(end 0.7874 -0.4064)
			(stroke
				(width 0.1524)
				(type default)
			)
			(layer "B.SilkS")
		)
		(fp_line
			(start 0.7874 -0.4064)
			(end -0.7874 -0.4064)
			(stroke
				(width 0.1524)
				(type default)
			)
			(layer "B.SilkS")
		)
		(fp_line
			(start -0.7874 0.4064)
			(end 0.7874 0.4064)
			(stroke
				(width 0.1524)
				(type default)
			)
			(layer "B.SilkS")
		)
		(fp_line
			(start -0.7874 -0.4064)
			(end -0.7874 0.4064)
			(stroke
				(width 0.1524)
				(type default)
			)
			(layer "B.SilkS")
		)
		(fp_line
			(start 0.67945 0.3048)
			(end 0.67945 -0.305054)
			(stroke
				(width 0.1)
				(type default)
			)
			(layer "B.Fab")
		)
		(fp_line
			(start 0.67945 -0.305054)
			(end 0.12065 -0.305054)
			(stroke
				(width 0.1)
				(type default)
			)
			(layer "B.Fab")
		)
		(fp_line
			(start 0.12065 0.3048)
			(end 0.67945 0.3048)
			(stroke
				(width 0.1)
				(type default)
			)
			(layer "B.Fab")
		)
		(fp_line
			(start 0.12065 0.2794)
			(end 0.12065 0.3048)
			(stroke
				(width 0.1)
				(type default)
			)
			(layer "B.Fab")
		)
		(fp_line
			(start 0.12065 -0.2794)
			(end -0.12065 -0.2794)
			(stroke
				(width 0.1)
				(type default)
			)
			(layer "B.Fab")
		)
		(fp_line
			(start 0.12065 -0.305054)
			(end 0.12065 -0.2794)
			(stroke
				(width 0.1)
				(type default)
			)
			(layer "B.Fab")
		)
		(fp_line
			(start -0.120396 0.3048)
			(end -0.120396 0.2794)
			(stroke
				(width 0.1)
				(type default)
			)
			(layer "B.Fab")
		)
		(fp_line
			(start -0.120396 0.2794)
			(end 0.12065 0.2794)
			(stroke
				(width 0.1)
				(type default)
			)
			(layer "B.Fab")
		)
		(fp_line
			(start -0.12065 -0.2794)
			(end -0.12065 -0.3048)
			(stroke
				(width 0.1)
				(type default)
			)
			(layer "B.Fab")
		)
		(fp_line
			(start -0.12065 -0.3048)
			(end -0.67945 -0.3048)
			(stroke
				(width 0.1)
				(type default)
			)
			(layer "B.Fab")
		)
		(fp_line
			(start -0.67945 0.3048)
			(end -0.120396 0.3048)
			(stroke
				(width 0.1)
				(type default)
			)
			(layer "B.Fab")
		)
		(fp_line
			(start -0.67945 -0.3048)
			(end -0.67945 0.3048)
			(stroke
				(width 0.1)
				(type default)
			)
			(layer "B.Fab")
		)
		(pad "1" smd circle
			(at 0.40005 0)
			(size 0 0)
			(layers "B.Cu" "B.Mask" "B.Paste")
			(net "PVDD18_S5_P1")
		)
		(pad "2" smd circle
			(at -0.40005 0)
			(size 0 0)
			(layers "B.Cu" "B.Mask" "B.Paste")
			(net "GND")
		)
	)
	(footprint ""
		(layer "B.Cu")
		(at 98.464878 -139.93241 90)
		(property "Reference" "PC11"
			(at 0 0 90)
			(layer "B.SilkS")
			(hide yes)
			(effects
				(font
					(size 1.27 1.27)
				)
				(justify mirror)
			)
		)
		(property "Value" ""
			(at 0 0 90)
			(layer "B.Fab")
			(effects
				(font
					(size 1.27 1.27)
				)
				(justify mirror)
			)
		)
		(duplicate_pad_numbers_are_jumpers no)
		(fp_line
			(start 0.7874 -0.4064)
			(end -0.7874 -0.4064)
			(stroke
				(width 0.1524)
				(type default)
			)
			(layer "B.SilkS")
		)
		(fp_line
			(start -0.7874 -0.4064)
			(end -0.7874 0.4064)
			(stroke
				(width 0.1524)
				(type default)
			)
			(layer "B.SilkS")
		)
		(fp_line
			(start 0.7874 0.4064)
			(end 0.7874 -0.4064)
			(stroke
				(width 0.1524)
				(type default)
			)
			(layer "B.SilkS")
		)
		(fp_line
			(start -0.7874 0.4064)
			(end 0.7874 0.4064)
			(stroke
				(width 0.1524)
				(type default)
			)
			(layer "B.SilkS")
		)
		(fp_line
			(start 0.67945 -0.305054)
			(end 0.12065 -0.305054)
			(stroke
				(width 0.1)
				(type default)
			)
			(layer "B.Fab")
		)
		(fp_line
			(start 0.12065 -0.305054)
			(end 0.12065 -0.2794)
			(stroke
				(width 0.1)
				(type default)
			)
			(layer "B.Fab")
		)
		(fp_line
			(start -0.12065 -0.3048)
			(end -0.67945 -0.3048)
			(stroke
				(width 0.1)
				(type default)
			)
			(layer "B.Fab")
		)
		(fp_line
			(start -0.67945 -0.3048)
			(end -0.67945 0.3048)
			(stroke
				(width 0.1)
				(type default)
			)
			(layer "B.Fab")
		)
		(fp_line
			(start 0.12065 -0.2794)
			(end -0.12065 -0.2794)
			(stroke
				(width 0.1)
				(type default)
			)
			(layer "B.Fab")
		)
		(fp_line
			(start -0.12065 -0.2794)
			(end -0.12065 -0.3048)
			(stroke
				(width 0.1)
				(type default)
			)
			(layer "B.Fab")
		)
		(fp_line
			(start 0.12065 0.2794)
			(end 0.12065 0.3048)
			(stroke
				(width 0.1)
				(type default)
			)
			(layer "B.Fab")
		)
		(fp_line
			(start -0.120396 0.2794)
			(end 0.12065 0.2794)
			(stroke
				(width 0.1)
				(type default)
			)
			(layer "B.Fab")
		)
		(fp_line
			(start 0.67945 0.3048)
			(end 0.67945 -0.305054)
			(stroke
				(width 0.1)
				(type default)
			)
			(layer "B.Fab")
		)
		(fp_line
			(start 0.12065 0.3048)
			(end 0.67945 0.3048)
			(stroke
				(width 0.1)
				(type default)
			)
			(layer "B.Fab")
		)
		(fp_line
			(start -0.120396 0.3048)
			(end -0.120396 0.2794)
			(stroke
				(width 0.1)
				(type default)
			)
			(layer "B.Fab")
		)
		(fp_line
			(start -0.67945 0.3048)
			(end -0.120396 0.3048)
			(stroke
				(width 0.1)
				(type default)
			)
			(layer "B.Fab")
		)
		(pad "1" smd circle
			(at 0.40005 0 270)
			(size 0 0)
			(layers "B.Cu" "B.Mask" "B.Paste")
			(net "PVDDCR_CPU0_P1_VCCS")
		)
		(pad "2" smd circle
			(at -0.40005 0 270)
			(size 0 0)
			(layers "B.Cu" "B.Mask" "B.Paste")
			(net "GND")
		)
	)
	(footprint ""
		(layer "B.Cu")
		(at 120.618504 -388.011162 -90)
		(property "Reference" "C451"
			(at 0 0 90)
			(layer "B.SilkS")
			(hide yes)
			(effects
				(font
					(size 1.27 1.27)
				)
				(justify mirror)
			)
		)
		(property "Value" ""
			(at 0 0 90)
			(layer "B.Fab")
			(effects
				(font
					(size 1.27 1.27)
				)
				(justify mirror)
			)
		)
		(duplicate_pad_numbers_are_jumpers no)
		(fp_line
			(start -0.299974 0.150114)
			(end 0.299974 0.150114)
			(stroke
				(width 0.1)
				(type default)
			)
			(layer "B.Fab")
		)
		(fp_line
			(start 0.299974 0.150114)
			(end 0.299974 -0.150114)
			(stroke
				(width 0.1)
				(type default)
			)
			(layer "B.Fab")
		)
		(fp_line
			(start -0.299974 -0.150114)
			(end -0.299974 0.150114)
			(stroke
				(width 0.1)
				(type default)
			)
			(layer "B.Fab")
		)
		(fp_line
			(start 0.299974 -0.150114)
			(end -0.299974 -0.150114)
			(stroke
				(width 0.1)
				(type default)
			)
			(layer "B.Fab")
		)
		(pad "1" smd rect
			(at 0.2667 0 90)
			(size 0.3048 0.381)
			(layers "B.Cu" "B.Mask" "B.Paste")
			(net "P0V9_CPU1_RT_2D")
		)
		(pad "2" smd rect
			(at -0.2667 0 90)
			(size 0.3048 0.381)
			(layers "B.Cu" "B.Mask" "B.Paste")
			(net "GND")
		)
	)
	(footprint ""
		(layer "B.Cu")
		(at 9.181338 -383.051558 -90)
		(property "Reference" "PC6624_1"
			(at 0 0 90)
			(layer "B.SilkS")
			(hide yes)
			(effects
				(font
					(size 1.27 1.27)
				)
				(justify mirror)
			)
		)
		(property "Value" ""
			(at 0 0 90)
			(layer "B.Fab")
			(effects
				(font
					(size 1.27 1.27)
				)
				(justify mirror)
			)
		)
		(duplicate_pad_numbers_are_jumpers no)
		(fp_line
			(start -1.524 0.762)
			(end 1.524 0.762)
			(stroke
				(width 0.1524)
				(type default)
			)
			(layer "B.SilkS")
		)
		(fp_line
			(start 1.524 0.762)
			(end 1.524 -0.762)
			(stroke
				(width 0.1524)
				(type default)
			)
			(layer "B.SilkS")
		)
		(fp_line
			(start -1.524 -0.762)
			(end -1.524 0.762)
			(stroke
				(width 0.1524)
				(type default)
			)
			(layer "B.SilkS")
		)
		(fp_line
			(start 1.524 -0.762)
			(end -1.524 -0.762)
			(stroke
				(width 0.1524)
				(type default)
			)
			(layer "B.SilkS")
		)
		(fp_line
			(start -1.1049 0.724916)
			(end -1.1049 -0.724916)
			(stroke
				(width 0.1)
				(type default)
			)
			(layer "B.Fab")
		)
		(fp_line
			(start 1.1049 0.724916)
			(end -1.1049 0.724916)
			(stroke
				(width 0.1)
				(type default)
			)
			(layer "B.Fab")
		)
		(fp_line
			(start -1.1049 -0.724916)
			(end 1.1049 -0.724916)
			(stroke
				(width 0.1)
				(type default)
			)
			(layer "B.Fab")
		)
		(fp_line
			(start 1.1049 -0.724916)
			(end 1.1049 0.724916)
			(stroke
				(width 0.1)
				(type default)
			)
			(layer "B.Fab")
		)
		(pad "1" smd rect
			(at 0.889 0 270)
			(size 1.016 1.27)
			(layers "B.Cu" "B.Mask" "B.Paste")
			(net "P0V9_CPU1_RT_2D")
		)
		(pad "2" smd rect
			(at -0.889 0 270)
			(size 1.016 1.27)
			(layers "B.Cu" "B.Mask" "B.Paste")
			(net "GND")
		)
	)
	(footprint ""
		(layer "B.Cu")
		(at 161.546286 -388.011162 -90)
		(property "Reference" "C427"
			(at 0 0 90)
			(layer "B.SilkS")
			(hide yes)
			(effects
				(font
					(size 1.27 1.27)
				)
				(justify mirror)
			)
		)
		(property "Value" ""
			(at 0 0 90)
			(layer "B.Fab")
			(effects
				(font
					(size 1.27 1.27)
				)
				(justify mirror)
			)
		)
		(duplicate_pad_numbers_are_jumpers no)
		(fp_line
			(start -0.299974 0.150114)
			(end 0.299974 0.150114)
			(stroke
				(width 0.1)
				(type default)
			)
			(layer "B.Fab")
		)
		(fp_line
			(start 0.299974 0.150114)
			(end 0.299974 -0.150114)
			(stroke
				(width 0.1)
				(type default)
			)
			(layer "B.Fab")
		)
		(fp_line
			(start -0.299974 -0.150114)
			(end -0.299974 0.150114)
			(stroke
				(width 0.1)
				(type default)
			)
			(layer "B.Fab")
		)
		(fp_line
			(start 0.299974 -0.150114)
			(end -0.299974 -0.150114)
			(stroke
				(width 0.1)
				(type default)
			)
			(layer "B.Fab")
		)
		(pad "1" smd rect
			(at 0.2667 0 90)
			(size 0.3048 0.381)
			(layers "B.Cu" "B.Mask" "B.Paste")
			(net "P0V9_CPU1_RT2_2A")
		)
		(pad "2" smd rect
			(at -0.2667 0 90)
			(size 0.3048 0.381)
			(layers "B.Cu" "B.Mask" "B.Paste")
			(net "GND")
		)
	)
	(footprint ""
		(layer "B.Cu")
		(at 103.924354 -186.811412 90)
		(property "Reference" "PC303_4"
			(at 0 0 90)
			(layer "B.SilkS")
			(hide yes)
			(effects
				(font
					(size 1.27 1.27)
				)
				(justify mirror)
			)
		)
		(property "Value" ""
			(at 0 0 90)
			(layer "B.Fab")
			(effects
				(font
					(size 1.27 1.27)
				)
				(justify mirror)
			)
		)
		(duplicate_pad_numbers_are_jumpers no)
		(fp_line
			(start 1.524 -0.762)
			(end -1.524 -0.762)
			(stroke
				(width 0.1524)
				(type default)
			)
			(layer "B.SilkS")
		)
		(fp_line
			(start -1.524 -0.762)
			(end -1.524 0.762)
			(stroke
				(width 0.1524)
				(type default)
			)
			(layer "B.SilkS")
		)
		(fp_line
			(start 1.524 0.762)
			(end 1.524 -0.762)
			(stroke
				(width 0.1524)
				(type default)
			)
			(layer "B.SilkS")
		)
		(fp_line
			(start -1.524 0.762)
			(end 1.524 0.762)
			(stroke
				(width 0.1524)
				(type default)
			)
			(layer "B.SilkS")
		)
		(fp_line
			(start 1.1049 -0.724916)
			(end 1.1049 0.724916)
			(stroke
				(width 0.1)
				(type default)
			)
			(layer "B.Fab")
		)
		(fp_line
			(start -1.1049 -0.724916)
			(end 1.1049 -0.724916)
			(stroke
				(width 0.1)
				(type default)
			)
			(layer "B.Fab")
		)
		(fp_line
			(start 1.1049 0.724916)
			(end -1.1049 0.724916)
			(stroke
				(width 0.1)
				(type default)
			)
			(layer "B.Fab")
		)
		(fp_line
			(start -1.1049 0.724916)
			(end -1.1049 -0.724916)
			(stroke
				(width 0.1)
				(type default)
			)
			(layer "B.Fab")
		)
		(pad "1" smd rect
			(at 0.889 0 90)
			(size 1.016 1.27)
			(layers "B.Cu" "B.Mask" "B.Paste")
			(net "PVDDCR_CPU0_P1")
		)
		(pad "2" smd rect
			(at -0.889 0 90)
			(size 1.016 1.27)
			(layers "B.Cu" "B.Mask" "B.Paste")
			(net "GND")
		)
	)
)
